(kicad_pcb
	(version 20260206)
	(generator "pcbnew")
	(generator_version "10.0")
	(general
		(thickness 1.6)
		(legacy_teardrops no)
	)
	(paper "A4")
	(title_block
		(title "Wiwynn_Tioga_Pass_MB.brd")
		(comment 1 "Tioga Pass / footprints 4587-4593 of 4770")
	)
	(layers
		(0 "F.Cu" signal "TOP")
		(4 "In1.Cu" signal "L2GND")
		(6 "In2.Cu" signal "L3")
		(8 "In3.Cu" signal "L4GND")
		(10 "In4.Cu" signal "L5")
		(12 "In5.Cu" signal "L6GND")
		(14 "In6.Cu" signal "L7VCC")
		(16 "In7.Cu" signal "L8VCC")
		(18 "In8.Cu" signal "L9GND")
		(20 "In9.Cu" signal "L10")
		(22 "In10.Cu" signal "L11GND")
		(24 "In11.Cu" signal "L12")
		(26 "In12.Cu" signal "L13GND")
		(2 "B.Cu" signal "BOTTOM")
		(9 "F.Adhes" user "F.Adhesive")
		(11 "B.Adhes" user "B.Adhesive")
		(13 "F.Paste" user "Package Geometry/Pastemask Top")
		(15 "B.Paste" user "Package Geometry/Pastemask Bottom")
		(5 "F.SilkS" user "Ref Des/Silkscreen Top")
		(7 "B.SilkS" user "Ref Des/Silkscreen Bottom")
		(1 "F.Mask" user "Board Geometry/Soldermask Top")
		(3 "B.Mask" user "Board Geometry/Soldermask Bottom")
		(17 "Dwgs.User" user "User.Drawings")
		(19 "Cmts.User" user "User.Comments")
		(21 "Eco1.User" user "User.Eco1")
		(23 "Eco2.User" user "User.Eco2")
		(25 "Edge.Cuts" user "Board Geometry/Outline")
		(27 "Margin" user)
		(31 "F.CrtYd" user "Package Geometry/Place Bound Top")
		(29 "B.CrtYd" user "Package Geometry/Place Bound Bottom")
		(35 "F.Fab" user "Ref Des/Assembly Top")
		(33 "B.Fab" user "Ref Des/Assembly Bottom")
	)
	(footprint ""
		(layer "B.Cu")
		(at 395.548358 -12.589002)
		(property "Reference" "C32W1"
			(at 0.8382 -0.67818 0)
			(unlocked yes)
			(layer "B.SilkS")
			(effects
				(font
					(size 0.4064 0.254)
					(thickness 0.1524)
				)
				(justify left mirror)
			)
		)
		(property "Value" ""
			(at 0 0 0)
			(layer "B.Fab")
			(effects
				(font
					(size 1.27 1.27)
				)
				(justify mirror)
			)
		)
		(duplicate_pad_numbers_are_jumpers no)
		(fp_poly
			(pts
				(xy -0.3048 -0.1016) (xy -0.3048 0.9906) (xy 0.3048 0.9906) (xy 0.3048 -0.1016)
			)
			(stroke
				(width 0)
				(type default)
			)
			(fill no)
			(layer "B.CrtYd")
		)
		(fp_line
			(start -0.3048 -0.1016)
			(end 0.3048 -0.1016)
			(stroke
				(width 0.1)
				(type default)
			)
			(layer "B.Fab")
		)
		(fp_line
			(start -0.3048 0.9906)
			(end -0.3048 -0.1016)
			(stroke
				(width 0.1)
				(type default)
			)
			(layer "B.Fab")
		)
		(fp_line
			(start 0.3048 -0.1016)
			(end 0.3048 0.9906)
			(stroke
				(width 0.1)
				(type default)
			)
			(layer "B.Fab")
		)
		(fp_line
			(start 0.3048 0.9906)
			(end -0.3048 0.9906)
			(stroke
				(width 0.1)
				(type default)
			)
			(layer "B.Fab")
		)
		(pad "1" smd rect
			(at 0 0 180)
			(size 0.508 0.508)
			(layers "B.Cu" "B.Mask" "B.Paste")
			(net "P1V8_M2")
		)
		(pad "2" smd rect
			(at 0 0.889 180)
			(size 0.508 0.508)
			(layers "B.Cu" "B.Mask" "B.Paste")
			(net "GND")
		)
		(zone
			(layer "B.Cu")
			(hatch none 0.5)
			(connect_pads
				(clearance 0)
			)
			(min_thickness 0.25)
			(keepout
				(tracks allowed)
				(vias not_allowed)
				(pads allowed)
				(copperpour not_allowed)
				(footprints allowed)
			)
			(placement
				(enabled no)
				(sheetname "")
			)
			(fill
				(thermal_gap 0.5)
				(thermal_bridge_width 0.5)
				(island_removal_mode 0)
			)
			(polygon
				(pts
					(xy 395.802358 -12.335002) (xy 395.294358 -12.335002) (xy 395.294358 -11.954002) (xy 395.802358 -11.954002)
				)
			)
		)
		(zone
			(layer "B.Cu")
			(hatch none 0.5)
			(connect_pads
				(clearance 0)
			)
			(min_thickness 0.25)
			(keepout
				(tracks not_allowed)
				(vias allowed)
				(pads allowed)
				(copperpour not_allowed)
				(footprints allowed)
			)
			(placement
				(enabled no)
				(sheetname "")
			)
			(fill
				(thermal_gap 0.5)
				(thermal_bridge_width 0.5)
				(island_removal_mode 0)
			)
			(polygon
				(pts
					(xy 395.802358 -11.954002) (xy 395.294358 -11.954002) (xy 395.294358 -12.335002) (xy 395.802358 -12.335002)
				)
			)
		)
	)
	(footprint ""
		(layer "B.Cu")
		(at 355.349048 -86.93404 180)
		(property "Reference" "SH3P1"
			(at 0 0 0)
			(layer "B.SilkS")
			(hide yes)
			(effects
				(font
					(size 1.27 1.27)
				)
				(justify mirror)
			)
		)
		(property "Value" ""
			(at 0 0 0)
			(layer "B.Fab")
			(effects
				(font
					(size 1.27 1.27)
				)
				(justify mirror)
			)
		)
		(duplicate_pad_numbers_are_jumpers no)
		(fp_poly
			(pts
				(xy 0.1651 -0.0508) (xy 0.1651 0.5842) (xy -0.1651 0.5842) (xy -0.1651 -0.0508)
			)
			(stroke
				(width 0)
				(type default)
			)
			(fill no)
			(layer "B.CrtYd")
		)
		(fp_line
			(start 0.1651 0.5842)
			(end 0.1651 -0.0508)
			(stroke
				(width 0.1)
				(type default)
			)
			(layer "B.Fab")
		)
		(fp_line
			(start 0.1651 -0.0508)
			(end -0.1651 -0.0508)
			(stroke
				(width 0.1)
				(type default)
			)
			(layer "B.Fab")
		)
		(fp_line
			(start -0.1651 0.5842)
			(end 0.1651 0.5842)
			(stroke
				(width 0.1)
				(type default)
			)
			(layer "B.Fab")
		)
		(fp_line
			(start -0.1651 -0.0508)
			(end -0.1651 0.5842)
			(stroke
				(width 0.1)
				(type default)
			)
			(layer "B.Fab")
		)
		(pad "1" smd custom
			(at 0 0 180)
			(size 0.0762 0.0762)
			(layers "B.Cu" "B.Mask" "B.Paste")
			(net "VSENSE_PVCCIO_CPU0_SKT_VSEN")
			(options
				(clearance outline)
				(anchor circle)
			)
			(primitives
				(gr_poly
					(pts
						(arc
							(start -0.1524 0.10795)
							(mid -0.098518 0.130268)
							(end -0.0762 0.18415)
						)
						(xy -0.0762 0.22225) (xy 0.0762 0.22225)
						(arc
							(start 0.0762 0.18415)
							(mid 0.098518 0.130268)
							(end 0.1524 0.10795)
						)
						(xy 0.1524 -0.22225) (xy -0.1524 -0.22225)
					)
					(width 0)
					(fill yes)
				)
			)
		)
		(pad "2" smd custom
			(at 0 0.5334)
			(size 0.0762 0.0762)
			(layers "B.Cu" "B.Mask" "B.Paste")
			(net "VSENSE_PVCCIO_CPU0_AVSP")
			(options
				(clearance outline)
				(anchor circle)
			)
			(primitives
				(gr_poly
					(pts
						(arc
							(start -0.1524 0.10795)
							(mid -0.098518 0.130268)
							(end -0.0762 0.18415)
						)
						(xy -0.0762 0.22225) (xy 0.0762 0.22225)
						(arc
							(start 0.0762 0.18415)
							(mid 0.098518 0.130268)
							(end 0.1524 0.10795)
						)
						(xy 0.1524 -0.22225) (xy -0.1524 -0.22225)
					)
					(width 0)
					(fill yes)
				)
			)
		)
	)
	(footprint ""
		(layer "B.Cu")
		(at 167.61587 -22.749764 -90)
		(property "Reference" "R6T3"
			(at 0 0 90)
			(layer "B.SilkS")
			(hide yes)
			(effects
				(font
					(size 1.27 1.27)
				)
				(justify mirror)
			)
		)
		(property "Value" ""
			(at 0 0 90)
			(layer "B.Fab")
			(effects
				(font
					(size 1.27 1.27)
				)
				(justify mirror)
			)
		)
		(duplicate_pad_numbers_are_jumpers no)
		(fp_poly
			(pts
				(xy 0.2794 -0.101854) (xy -0.2794 -0.101854) (xy -0.2794 0.990346) (xy 0.2794 0.990346)
			)
			(stroke
				(width 0)
				(type default)
			)
			(fill no)
			(layer "B.CrtYd")
		)
		(fp_line
			(start -0.2794 0.990346)
			(end -0.2794 -0.101854)
			(stroke
				(width 0.1)
				(type default)
			)
			(layer "B.Fab")
		)
		(fp_line
			(start 0.2794 0.990346)
			(end -0.2794 0.990346)
			(stroke
				(width 0.1)
				(type default)
			)
			(layer "B.Fab")
		)
		(fp_line
			(start -0.2794 -0.101854)
			(end 0.2794 -0.101854)
			(stroke
				(width 0.1)
				(type default)
			)
			(layer "B.Fab")
		)
		(fp_line
			(start 0.2794 -0.101854)
			(end 0.2794 0.990346)
			(stroke
				(width 0.1)
				(type default)
			)
			(layer "B.Fab")
		)
		(pad "1" smd rect
			(at 0 0 90)
			(size 0.508 0.508)
			(layers "B.Cu" "B.Mask" "B.Paste")
			(net "SMB_DDR_GHJ_SCL_G_R")
		)
		(pad "2" smd rect
			(at 0 0.889 90)
			(size 0.508 0.508)
			(layers "B.Cu" "B.Mask" "B.Paste")
			(net "SMB_DDR_GHJ_SCL_G")
		)
		(zone
			(layer "B.Cu")
			(hatch none 0.5)
			(connect_pads
				(clearance 0)
			)
			(min_thickness 0.25)
			(keepout
				(tracks not_allowed)
				(vias allowed)
				(pads allowed)
				(copperpour not_allowed)
				(footprints allowed)
			)
			(placement
				(enabled no)
				(sheetname "")
			)
			(fill
				(thermal_gap 0.5)
				(thermal_bridge_width 0.5)
				(island_removal_mode 0)
			)
			(polygon
				(pts
					(xy 166.981124 -22.495764) (xy 166.981124 -23.003764) (xy 167.362124 -23.003764) (xy 167.362124 -22.495764)
				)
			)
		)
		(zone
			(layer "B.Cu")
			(hatch none 0.5)
			(connect_pads
				(clearance 0)
			)
			(min_thickness 0.25)
			(keepout
				(tracks allowed)
				(vias not_allowed)
				(pads allowed)
				(copperpour not_allowed)
				(footprints allowed)
			)
			(placement
				(enabled no)
				(sheetname "")
			)
			(fill
				(thermal_gap 0.5)
				(thermal_bridge_width 0.5)
				(island_removal_mode 0)
			)
			(polygon
				(pts
					(xy 167.362124 -22.495764) (xy 167.362124 -23.003764) (xy 166.981124 -23.003764) (xy 166.981124 -22.495764)
				)
			)
		)
	)
	(footprint ""
		(layer "B.Cu")
		(at 276.836886 -77.82814)
		(property "Reference" "C4P4"
			(at 0 0 0)
			(layer "B.SilkS")
			(hide yes)
			(effects
				(font
					(size 1.27 1.27)
				)
				(justify mirror)
			)
		)
		(property "Value" ""
			(at 0 0 0)
			(layer "B.Fab")
			(effects
				(font
					(size 1.27 1.27)
				)
				(justify mirror)
			)
		)
		(duplicate_pad_numbers_are_jumpers no)
		(fp_poly
			(pts
				(xy 0.7239 -0.2159) (xy -0.7239 -0.2159) (xy -0.7239 1.9939) (xy 0.7239 1.9939)
			)
			(stroke
				(width 0)
				(type default)
			)
			(fill no)
			(layer "B.CrtYd")
		)
		(fp_line
			(start -0.7239 -0.2159)
			(end 0.7239 -0.2159)
			(stroke
				(width 0.1)
				(type default)
			)
			(layer "B.Fab")
		)
		(fp_line
			(start -0.7239 1.9939)
			(end -0.7239 -0.2159)
			(stroke
				(width 0.1)
				(type default)
			)
			(layer "B.Fab")
		)
		(fp_line
			(start 0.7239 -0.2159)
			(end 0.7239 1.9939)
			(stroke
				(width 0.1)
				(type default)
			)
			(layer "B.Fab")
		)
		(fp_line
			(start 0.7239 1.9939)
			(end -0.7239 1.9939)
			(stroke
				(width 0.1)
				(type default)
			)
			(layer "B.Fab")
		)
		(pad "1" smd rect
			(at 0 0 180)
			(size 1.27 1.016)
			(layers "B.Cu" "B.Mask" "B.Paste")
			(net "PVCCMCP_CPU0")
		)
		(pad "2" smd rect
			(at 0 1.778 180)
			(size 1.27 1.016)
			(layers "B.Cu" "B.Mask" "B.Paste")
			(net "GND")
		)
		(zone
			(layer "B.Cu")
			(hatch none 0.5)
			(connect_pads
				(clearance 0)
			)
			(min_thickness 0.25)
			(keepout
				(tracks not_allowed)
				(vias allowed)
				(pads allowed)
				(copperpour not_allowed)
				(footprints allowed)
			)
			(placement
				(enabled no)
				(sheetname "")
			)
			(fill
				(thermal_gap 0.5)
				(thermal_bridge_width 0.5)
				(island_removal_mode 0)
			)
			(polygon
				(pts
					(xy 277.471886 -77.32014) (xy 276.201886 -77.32014) (xy 276.201886 -76.55814) (xy 277.471886 -76.55814)
				)
			)
		)
	)
	(footprint ""
		(layer "B.Cu")
		(at 111.983012 -29.94152 90)
		(property "Reference" "R7U2"
			(at 0 0 90)
			(layer "B.SilkS")
			(hide yes)
			(effects
				(font
					(size 1.27 1.27)
				)
				(justify mirror)
			)
		)
		(property "Value" ""
			(at 0 0 90)
			(layer "B.Fab")
			(effects
				(font
					(size 1.27 1.27)
				)
				(justify mirror)
			)
		)
		(duplicate_pad_numbers_are_jumpers no)
		(fp_poly
			(pts
				(xy 0.2794 -0.1016) (xy -0.2794 -0.1016) (xy -0.2794 0.9906) (xy 0.2794 0.9906)
			)
			(stroke
				(width 0)
				(type default)
			)
			(fill no)
			(layer "B.CrtYd")
		)
		(fp_line
			(start 0.2794 -0.1016)
			(end 0.2794 0.9906)
			(stroke
				(width 0.1)
				(type default)
			)
			(layer "B.Fab")
		)
		(fp_line
			(start -0.2794 -0.1016)
			(end 0.2794 -0.1016)
			(stroke
				(width 0.1)
				(type default)
			)
			(layer "B.Fab")
		)
		(fp_line
			(start 0.2794 0.9906)
			(end -0.2794 0.9906)
			(stroke
				(width 0.1)
				(type default)
			)
			(layer "B.Fab")
		)
		(fp_line
			(start -0.2794 0.9906)
			(end -0.2794 -0.1016)
			(stroke
				(width 0.1)
				(type default)
			)
			(layer "B.Fab")
		)
		(pad "1" smd rect
			(at 0 0 270)
			(size 0.508 0.508)
			(layers "B.Cu" "B.Mask" "B.Paste")
			(net "VSENSE_PVDDQ_GHJ_P")
		)
		(pad "2" smd rect
			(at 0 0.889 270)
			(size 0.508 0.508)
			(layers "B.Cu" "B.Mask" "B.Paste")
			(net "VSENSE_PVDDQ_GHJ_N")
		)
		(zone
			(layer "B.Cu")
			(hatch none 0.5)
			(connect_pads
				(clearance 0)
			)
			(min_thickness 0.25)
			(keepout
				(tracks allowed)
				(vias not_allowed)
				(pads allowed)
				(copperpour not_allowed)
				(footprints allowed)
			)
			(placement
				(enabled no)
				(sheetname "")
			)
			(fill
				(thermal_gap 0.5)
				(thermal_bridge_width 0.5)
				(island_removal_mode 0)
			)
			(polygon
				(pts
					(xy 112.237012 -30.19552) (xy 112.237012 -29.68752) (xy 112.618012 -29.68752) (xy 112.618012 -30.19552)
				)
			)
		)
		(zone
			(layer "B.Cu")
			(hatch none 0.5)
			(connect_pads
				(clearance 0)
			)
			(min_thickness 0.25)
			(keepout
				(tracks not_allowed)
				(vias allowed)
				(pads allowed)
				(copperpour not_allowed)
				(footprints allowed)
			)
			(placement
				(enabled no)
				(sheetname "")
			)
			(fill
				(thermal_gap 0.5)
				(thermal_bridge_width 0.5)
				(island_removal_mode 0)
			)
			(polygon
				(pts
					(xy 112.618012 -30.19552) (xy 112.618012 -29.68752) (xy 112.237012 -29.68752) (xy 112.237012 -30.19552)
				)
			)
		)
	)
	(footprint ""
		(layer "B.Cu")
		(at 402.463 -153.289 -90)
		(property "Reference" "R2L25"
			(at 0 0 90)
			(layer "B.SilkS")
			(hide yes)
			(effects
				(font
					(size 1.27 1.27)
				)
				(justify mirror)
			)
		)
		(property "Value" ""
			(at 0 0 90)
			(layer "B.Fab")
			(effects
				(font
					(size 1.27 1.27)
				)
				(justify mirror)
			)
		)
		(duplicate_pad_numbers_are_jumpers no)
		(fp_poly
			(pts
				(xy 0.2794 -0.1016) (xy -0.2794 -0.1016) (xy -0.2794 0.9906) (xy 0.2794 0.9906)
			)
			(stroke
				(width 0)
				(type default)
			)
			(fill no)
			(layer "B.CrtYd")
		)
		(fp_line
			(start -0.2794 0.9906)
			(end -0.2794 -0.1016)
			(stroke
				(width 0.1)
				(type default)
			)
			(layer "B.Fab")
		)
		(fp_line
			(start 0.2794 0.9906)
			(end -0.2794 0.9906)
			(stroke
				(width 0.1)
				(type default)
			)
			(layer "B.Fab")
		)
		(fp_line
			(start -0.2794 -0.1016)
			(end 0.2794 -0.1016)
			(stroke
				(width 0.1)
				(type default)
			)
			(layer "B.Fab")
		)
		(fp_line
			(start 0.2794 -0.1016)
			(end 0.2794 0.9906)
			(stroke
				(width 0.1)
				(type default)
			)
			(layer "B.Fab")
		)
		(pad "1" smd rect
			(at 0 0 90)
			(size 0.508 0.508)
			(layers "B.Cu" "B.Mask" "B.Paste")
			(net "P3V3_STBY")
		)
		(pad "2" smd rect
			(at 0 0.889 90)
			(size 0.508 0.508)
			(layers "B.Cu" "B.Mask" "B.Paste")
			(net "VID_PCH_CORE_PVNN_AUX_VID_1")
		)
		(zone
			(layer "B.Cu")
			(hatch none 0.5)
			(connect_pads
				(clearance 0)
			)
			(min_thickness 0.25)
			(keepout
				(tracks not_allowed)
				(vias allowed)
				(pads allowed)
				(copperpour not_allowed)
				(footprints allowed)
			)
			(placement
				(enabled no)
				(sheetname "")
			)
			(fill
				(thermal_gap 0.5)
				(thermal_bridge_width 0.5)
				(island_removal_mode 0)
			)
			(polygon
				(pts
					(xy 401.828 -153.035) (xy 401.828 -153.543) (xy 402.209 -153.543) (xy 402.209 -153.035)
				)
			)
		)
		(zone
			(layer "B.Cu")
			(hatch none 0.5)
			(connect_pads
				(clearance 0)
			)
			(min_thickness 0.25)
			(keepout
				(tracks allowed)
				(vias not_allowed)
				(pads allowed)
				(copperpour not_allowed)
				(footprints allowed)
			)
			(placement
				(enabled no)
				(sheetname "")
			)
			(fill
				(thermal_gap 0.5)
				(thermal_bridge_width 0.5)
				(island_removal_mode 0)
			)
			(polygon
				(pts
					(xy 402.209 -153.035) (xy 402.209 -153.543) (xy 401.828 -153.543) (xy 401.828 -153.035)
				)
			)
		)
	)
	(footprint ""
		(layer "B.Cu")
		(at 181.339998 2.425192 180)
		(property "Reference" "R6U15"
			(at 0 0 0)
			(layer "B.SilkS")
			(hide yes)
			(effects
				(font
					(size 1.27 1.27)
				)
				(justify mirror)
			)
		)
		(property "Value" ""
			(at 0 0 0)
			(layer "B.Fab")
			(effects
				(font
					(size 1.27 1.27)
				)
				(justify mirror)
			)
		)
		(duplicate_pad_numbers_are_jumpers no)
		(fp_rect
			(start 0.2794 -0.1016)
			(end -0.2794 0.9906)
			(stroke
				(width 0)
				(type default)
			)
			(fill no)
			(layer "B.CrtYd")
		)
		(fp_line
			(start 0.2794 0.9906)
			(end -0.2794 0.9906)
			(stroke
				(width 0.1)
				(type default)
			)
			(layer "B.Fab")
		)
		(fp_line
			(start 0.2794 -0.1016)
			(end 0.2794 0.9906)
			(stroke
				(width 0.1)
				(type default)
			)
			(layer "B.Fab")
		)
		(fp_line
			(start -0.2794 0.9906)
			(end -0.2794 -0.1016)
			(stroke
				(width 0.1)
				(type default)
			)
			(layer "B.Fab")
		)
		(fp_line
			(start -0.2794 -0.1016)
			(end 0.2794 -0.1016)
			(stroke
				(width 0.1)
				(type default)
			)
			(layer "B.Fab")
		)
		(pad "1" smd rect
			(at 0 0)
			(size 0.508 0.508)
			(layers "B.Cu" "B.Mask" "B.Paste")
			(net "P3V3")
		)
		(pad "2" smd rect
			(at 0 0.889)
			(size 0.508 0.508)
			(layers "B.Cu" "B.Mask" "B.Paste")
			(net "FM_PVTT_ABC_EN_R")
		)
		(zone
			(layer "B.Cu")
			(hatch none 0.5)
			(connect_pads
				(clearance 0)
			)
			(min_thickness 0.25)
			(keepout
				(tracks not_allowed)
				(vias allowed)
				(pads allowed)
				(copperpour not_allowed)
				(footprints allowed)
			)
			(placement
				(enabled no)
				(sheetname "")
			)
			(fill
				(thermal_gap 0.5)
				(thermal_bridge_width 0.5)
				(island_removal_mode 0)
			)
			(polygon
				(pts
					(xy 181.085998 2.171192) (xy 181.593998 2.171192) (xy 181.593998 1.790192) (xy 181.085998 1.790192)
				)
			)
		)
		(zone
			(layer "B.Cu")
			(hatch none 0.5)
			(connect_pads
				(clearance 0)
			)
			(min_thickness 0.25)
			(keepout
				(tracks allowed)
				(vias not_allowed)
				(pads allowed)
				(copperpour not_allowed)
				(footprints allowed)
			)
			(placement
				(enabled no)
				(sheetname "")
			)
			(fill
				(thermal_gap 0.5)
				(thermal_bridge_width 0.5)
				(island_removal_mode 0)
			)
			(polygon
				(pts
					(xy 181.085998 2.171192) (xy 181.593998 2.171192) (xy 181.593998 1.790192) (xy 181.085998 1.790192)
				)
			)
		)
	)
)
